# BASEBOARD_FAB2 (Tioga Pass) — schematic netlist excerpt (pin names and nets, part order shuffled) for the footprints in the layout excerpt that follows; sources: Cadence DE-HDL packaged netlist, KiCad conversion of Wiwynn_Tioga_Pass_MB.brd

C4B6  CAP  0.027UF 16V 10% X7R  pkg 0402  page 234 : A = VR_PVPP_KLM_SS ; B = AGND_PVPP_KLM
R4D42  RES  1.00K 1% CHIP  pkg 0402  page 213 : A = P3V3_STBY ; B = PWRGD_PVCCIO_CPU1_R
C7A30  CAP  22UF 4V 20% X6S  pkg 0805LF  page 236 : A = PVNN_PCH_STBY ; B = GND

(kicad_pcb
	(version 20260206)
	(generator "pcbnew")
	(generator_version "10.0")
	(general
		(thickness 1.6)
		(legacy_teardrops no)
	)
	(paper "A4")
	(title_block
		(title "Wiwynn_Tioga_Pass_MB.brd")
		(comment 1 "Tioga Pass / footprints 1782-1784 of 4770")
	)
	(layers
		(0 "F.Cu" signal "TOP")
		(4 "In1.Cu" signal "L2GND")
		(6 "In2.Cu" signal "L3")
		(8 "In3.Cu" signal "L4GND")
		(10 "In4.Cu" signal "L5")
		(12 "In5.Cu" signal "L6GND")
		(14 "In6.Cu" signal "L7VCC")
		(16 "In7.Cu" signal "L8VCC")
		(18 "In8.Cu" signal "L9GND")
		(20 "In9.Cu" signal "L10")
		(22 "In10.Cu" signal "L11GND")
		(24 "In11.Cu" signal "L12")
		(26 "In12.Cu" signal "L13GND")
		(2 "B.Cu" signal "BOTTOM")
		(9 "F.Adhes" user "F.Adhesive")
		(11 "B.Adhes" user "B.Adhesive")
		(13 "F.Paste" user "Package Geometry/Pastemask Top")
		(15 "B.Paste" user "Package Geometry/Pastemask Bottom")
		(5 "F.SilkS" user "Ref Des/Silkscreen Top")
		(7 "B.SilkS" user "Ref Des/Silkscreen Bottom")
		(1 "F.Mask" user "Board Geometry/Soldermask Top")
		(3 "B.Mask" user "Board Geometry/Soldermask Bottom")
		(17 "Dwgs.User" user "User.Drawings")
		(19 "Cmts.User" user "User.Comments")
		(21 "Eco1.User" user "User.Eco1")
		(23 "Eco2.User" user "User.Eco2")
		(25 "Edge.Cuts" user "Board Geometry/Outline")
		(27 "Margin" user)
		(31 "F.CrtYd" user "Package Geometry/Place Bound Top")
		(29 "B.CrtYd" user "Package Geometry/Place Bound Bottom")
		(35 "F.Fab" user "Ref Des/Assembly Top")
		(33 "B.Fab" user "Ref Des/Assembly Bottom")
	)
	(footprint ""
		(layer "F.Cu")
		(at 167.259 -71.5264)
		(property "Reference" "R4D42"
			(at 0 0 0)
			(layer "F.SilkS")
			(hide yes)
			(effects
				(font
					(size 1.27 1.27)
				)
			)
		)
		(property "Value" ""
			(at 0 0 0)
			(layer "F.Fab")
			(effects
				(font
					(size 1.27 1.27)
				)
			)
		)
		(duplicate_pad_numbers_are_jumpers no)
		(fp_poly
			(pts
				(xy -0.2794 -0.1016) (xy 0.2794 -0.1016) (xy 0.2794 0.9906) (xy -0.2794 0.9906)
			)
			(stroke
				(width 0)
				(type default)
			)
			(fill no)
			(layer "F.CrtYd")
		)
		(fp_line
			(start -0.2794 -0.1016)
			(end -0.2794 0.9906)
			(stroke
				(width 0.1)
				(type default)
			)
			(layer "F.Fab")
		)
		(fp_line
			(start -0.2794 0.9906)
			(end 0.2794 0.9906)
			(stroke
				(width 0.1)
				(type default)
			)
			(layer "F.Fab")
		)
		(fp_line
			(start 0.2794 -0.1016)
			(end -0.2794 -0.1016)
			(stroke
				(width 0.1)
				(type default)
			)
			(layer "F.Fab")
		)
		(fp_line
			(start 0.2794 0.9906)
			(end 0.2794 -0.1016)
			(stroke
				(width 0.1)
				(type default)
			)
			(layer "F.Fab")
		)
		(pad "1" smd rect
			(at 0 0)
			(size 0.508 0.508)
			(layers "F.Cu" "F.Mask" "F.Paste")
			(net "P3V3_STBY")
		)
		(pad "2" smd rect
			(at 0 0.889)
			(size 0.508 0.508)
			(layers "F.Cu" "F.Mask" "F.Paste")
			(net "PWRGD_PVCCIO_CPU1_R")
		)
		(zone
			(layer "F.Cu")
			(hatch none 0.5)
			(connect_pads
				(clearance 0)
			)
			(min_thickness 0.25)
			(keepout
				(tracks allowed)
				(vias not_allowed)
				(pads allowed)
				(copperpour not_allowed)
				(footprints allowed)
			)
			(placement
				(enabled no)
				(sheetname "")
			)
			(fill
				(thermal_gap 0.5)
				(thermal_bridge_width 0.5)
				(island_removal_mode 0)
			)
			(polygon
				(pts
					(xy 167.005 -71.2724) (xy 167.513 -71.2724) (xy 167.513 -70.8914) (xy 167.005 -70.8914)
				)
			)
		)
		(zone
			(layer "F.Cu")
			(hatch none 0.5)
			(connect_pads
				(clearance 0)
			)
			(min_thickness 0.25)
			(keepout
				(tracks not_allowed)
				(vias allowed)
				(pads allowed)
				(copperpour not_allowed)
				(footprints allowed)
			)
			(placement
				(enabled no)
				(sheetname "")
			)
			(fill
				(thermal_gap 0.5)
				(thermal_bridge_width 0.5)
				(island_removal_mode 0)
			)
			(polygon
				(pts
					(xy 167.005 -70.8914) (xy 167.513 -70.8914) (xy 167.513 -71.2724) (xy 167.005 -71.2724)
				)
			)
		)
	)
	(footprint ""
		(layer "F.Cu")
		(at 379.3109 -137.4648)
		(property "Reference" "C7A30"
			(at 0 0 0)
			(layer "F.SilkS")
			(hide yes)
			(effects
				(font
					(size 1.27 1.27)
				)
			)
		)
		(property "Value" ""
			(at 0 0 0)
			(layer "F.Fab")
			(effects
				(font
					(size 1.27 1.27)
				)
			)
		)
		(duplicate_pad_numbers_are_jumpers no)
		(fp_rect
			(start -0.7239 1.9939)
			(end 0.7239 -0.2159)
			(stroke
				(width 0)
				(type default)
			)
			(fill no)
			(layer "F.CrtYd")
		)
		(fp_line
			(start -0.7239 -0.2159)
			(end -0.7239 1.9939)
			(stroke
				(width 0.1)
				(type default)
			)
			(layer "F.Fab")
		)
		(fp_line
			(start -0.7239 1.9939)
			(end 0.7239 1.9939)
			(stroke
				(width 0.1)
				(type default)
			)
			(layer "F.Fab")
		)
		(fp_line
			(start 0.7239 -0.2159)
			(end -0.7239 -0.2159)
			(stroke
				(width 0.1)
				(type default)
			)
			(layer "F.Fab")
		)
		(fp_line
			(start 0.7239 1.9939)
			(end 0.7239 -0.2159)
			(stroke
				(width 0.1)
				(type default)
			)
			(layer "F.Fab")
		)
		(pad "1" smd rect
			(at 0 0)
			(size 1.27 1.016)
			(layers "F.Cu" "F.Mask" "F.Paste")
			(net "PVNN_PCH_STBY")
		)
		(pad "2" smd rect
			(at 0 1.778)
			(size 1.27 1.016)
			(layers "F.Cu" "F.Mask" "F.Paste")
			(net "GND")
		)
		(zone
			(layer "F.Cu")
			(hatch none 0.5)
			(connect_pads
				(clearance 0)
			)
			(min_thickness 0.25)
			(keepout
				(tracks not_allowed)
				(vias allowed)
				(pads allowed)
				(copperpour not_allowed)
				(footprints allowed)
			)
			(placement
				(enabled no)
				(sheetname "")
			)
			(fill
				(thermal_gap 0.5)
				(thermal_bridge_width 0.5)
				(island_removal_mode 0)
			)
			(polygon
				(pts
					(xy 378.6759 -136.1948) (xy 379.9459 -136.1948) (xy 379.9459 -136.9568) (xy 378.6759 -136.9568)
				)
			)
		)
	)
	(footprint ""
		(layer "F.Cu")
		(at 173.355 -131.5085)
		(property "Reference" "C4B6"
			(at 0 0 0)
			(layer "F.SilkS")
			(hide yes)
			(effects
				(font
					(size 1.27 1.27)
				)
			)
		)
		(property "Value" ""
			(at 0 0 0)
			(layer "F.Fab")
			(effects
				(font
					(size 1.27 1.27)
				)
			)
		)
		(duplicate_pad_numbers_are_jumpers no)
		(fp_poly
			(pts
				(xy 0.3048 -0.1016) (xy 0.3048 0.9906) (xy -0.3048 0.9906) (xy -0.3048 -0.1016)
			)
			(stroke
				(width 0)
				(type default)
			)
			(fill no)
			(layer "F.CrtYd")
		)
		(fp_line
			(start -0.3048 -0.1016)
			(end -0.3048 0.9906)
			(stroke
				(width 0.1)
				(type default)
			)
			(layer "F.Fab")
		)
		(fp_line
			(start -0.3048 0.9906)
			(end 0.3048 0.9906)
			(stroke
				(width 0.1)
				(type default)
			)
			(layer "F.Fab")
		)
		(fp_line
			(start 0.3048 -0.1016)
			(end -0.3048 -0.1016)
			(stroke
				(width 0.1)
				(type default)
			)
			(layer "F.Fab")
		)
		(fp_line
			(start 0.3048 0.9906)
			(end 0.3048 -0.1016)
			(stroke
				(width 0.1)
				(type default)
			)
			(layer "F.Fab")
		)
		(pad "1" smd rect
			(at 0 0)
			(size 0.508 0.508)
			(layers "F.Cu" "F.Mask" "F.Paste")
			(net "VR_PVPP_KLM_SS")
		)
		(pad "2" smd rect
			(at 0 0.889)
			(size 0.508 0.508)
			(layers "F.Cu" "F.Mask" "F.Paste")
			(net "AGND_PVPP_KLM")
		)
		(zone
			(layer "F.Cu")
			(hatch none 0.5)
			(connect_pads
				(clearance 0)
			)
			(min_thickness 0.25)
			(keepout
				(tracks allowed)
				(vias not_allowed)
				(pads allowed)
				(copperpour not_allowed)
				(footprints allowed)
			)
			(placement
				(enabled no)
				(sheetname "")
			)
			(fill
				(thermal_gap 0.5)
				(thermal_bridge_width 0.5)
				(island_removal_mode 0)
			)
			(polygon
				(pts
					(xy 173.101 -131.2545) (xy 173.609 -131.2545) (xy 173.609 -130.8735) (xy 173.101 -130.8735)
				)
			)
		)
		(zone
			(layer "F.Cu")
			(hatch none 0.5)
			(connect_pads
				(clearance 0)
			)
			(min_thickness 0.25)
			(keepout
				(tracks not_allowed)
				(vias allowed)
				(pads allowed)
				(copperpour not_allowed)
				(footprints allowed)
			)
			(placement
				(enabled no)
				(sheetname "")
			)
			(fill
				(thermal_gap 0.5)
				(thermal_bridge_width 0.5)
				(island_removal_mode 0)
			)
			(polygon
				(pts
					(xy 173.101 -130.8735) (xy 173.609 -130.8735) (xy 173.609 -131.2545) (xy 173.101 -131.2545)
				)
			)
		)
	)
)
